(kicad_pcb
	(version 20260206)
	(generator "pcbnew")
	(generator_version "10.0")
	(general
		(thickness 1.6)
		(legacy_teardrops no)
	)
	(paper "A4")
	(title_block
		(title "netronome-mezz — pcbd0082-001_rev01_jul9_a.brd")
		(comment 1 "Open CloudServer (Microsoft) / footprint 225 of 714 (U1), pads 234-351 of 1022")
	)
	(layers
		(0 "F.Cu" signal "TOP")
		(4 "In1.Cu" signal "02_GND")
		(6 "In2.Cu" signal "03_SIG")
		(8 "In3.Cu" signal "04_SIG")
		(10 "In4.Cu" signal "05_GND")
		(12 "In5.Cu" signal "06_PWR1")
		(14 "In6.Cu" signal "07_SIG")
		(16 "In7.Cu" signal "08_SIG")
		(18 "In8.Cu" signal "09_GND")
		(2 "B.Cu" signal "BOTTOM")
		(9 "F.Adhes" user "F.Adhesive")
		(11 "B.Adhes" user "B.Adhesive")
		(13 "F.Paste" user "Package Geometry/Pastemask Top")
		(15 "B.Paste" user "Package Geometry/Pastemask Bottom")
		(5 "F.SilkS" user "Ref Des/Silkscreen Top")
		(7 "B.SilkS" user "Ref Des/Silkscreen Bottom")
		(1 "F.Mask" user "Board Geometry/Soldermask Top")
		(3 "B.Mask" user "Board Geometry/Soldermask Bottom")
		(17 "Dwgs.User" user "User.Drawings")
		(19 "Cmts.User" user "User.Comments")
		(21 "Eco1.User" user "User.Eco1")
		(23 "Eco2.User" user "User.Eco2")
		(25 "Edge.Cuts" user "Board Geometry/Outline")
		(27 "Margin" user)
		(31 "F.CrtYd" user "Package Geometry/Place Bound Top")
		(29 "B.CrtYd" user "Package Geometry/Place Bound Bottom")
		(35 "F.Fab" user "Ref Des/Assembly Top")
		(33 "B.Fab" user "Ref Des/Assembly Bottom")
		(45 "User.4" user "COMPVAL_TYPE_BOTTOM")
	)
	(footprint ""
		(layer "F.Cu")
		(at 54.737 18.542 180)
		(property "Reference" "U1"
			(at -12.192 17.9705 0)
			(unlocked yes)
			(layer "F.SilkS")
			(effects
				(font
					(size 1.27 0.9652)
					(thickness 0.1524)
				)
				(justify left)
			)
		)
		(property "Value" "*"
			(at -0.4826 1.74879 180)
			(unlocked yes)
			(layer "F.Fab")
			(hide yes)
			(effects
				(font
					(size 1.27 0.9652)
					(thickness 0.000001)
				)
				(justify left)
			)
		)
		(property "Device Type" "ICBG0048"
			(at -0.4826 1.74879 180)
			(unlocked yes)
			(layer "F.Fab")
			(hide yes)
			(effects
				(font
					(size 1.27 0.9652)
					(thickness 0.000001)
				)
				(justify left)
			)
		)
		(duplicate_pad_numbers_are_jumpers no)
		(pad "AG10" smd circle
			(at -6.500012 10.500004 180)
			(size 0.508 0.508)
			(layers "F.Cu" "F.Mask" "F.Paste")
			(net "GND")
		)
		(pad "AG11" smd circle
			(at -5.499989 10.500004 180)
			(size 0.508 0.508)
			(layers "F.Cu" "F.Mask" "F.Paste")
			(net "GND")
		)
		(pad "AG12" smd circle
			(at -4.499991 10.500004 180)
			(size 0.508 0.508)
			(layers "F.Cu" "F.Mask" "F.Paste")
			(net "NFP_PCIE0_PET0_N")
		)
		(pad "AG13" smd circle
			(at -3.499993 10.500004 180)
			(size 0.508 0.508)
			(layers "F.Cu" "F.Mask" "F.Paste")
			(net "GND")
		)
		(pad "AG14" smd circle
			(at -2.499995 10.500004 180)
			(size 0.508 0.508)
			(layers "F.Cu" "F.Mask" "F.Paste")
			(net "NFP_PCIE0_PET2_N")
		)
		(pad "AG15" smd circle
			(at -1.499997 10.500004 180)
			(size 0.508 0.508)
			(layers "F.Cu" "F.Mask" "F.Paste")
			(net "GND")
		)
		(pad "AG16" smd circle
			(at -0.499999 10.500004 180)
			(size 0.508 0.508)
			(layers "F.Cu" "F.Mask" "F.Paste")
			(net "NFP_PCIE0_PET4_N")
		)
		(pad "AG17" smd circle
			(at 0.499999 10.500004 180)
			(size 0.508 0.508)
			(layers "F.Cu" "F.Mask" "F.Paste")
			(net "GND")
		)
		(pad "AG18" smd circle
			(at 1.499997 10.500004 180)
			(size 0.508 0.508)
			(layers "F.Cu" "F.Mask" "F.Paste")
			(net "NFP_PCIE0_PET6_N")
		)
		(pad "AG19" smd circle
			(at 2.499995 10.500004 180)
			(size 0.508 0.508)
			(layers "F.Cu" "F.Mask" "F.Paste")
			(net "GND")
		)
		(pad "AG20" smd circle
			(at 3.499993 10.500004 180)
			(size 0.508 0.508)
			(layers "F.Cu" "F.Mask" "F.Paste")
			(net "NFP_SERDES0_RX0_N")
		)
		(pad "AG21" smd circle
			(at 4.499991 10.500004 180)
			(size 0.508 0.508)
			(layers "F.Cu" "F.Mask" "F.Paste")
			(net "GND")
		)
		(pad "AG22" smd circle
			(at 5.499989 10.500004 180)
			(size 0.508 0.508)
			(layers "F.Cu" "F.Mask" "F.Paste")
			(net "GND")
		)
		(pad "AG23" smd circle
			(at 6.500012 10.500004 180)
			(size 0.508 0.508)
			(layers "F.Cu" "F.Mask" "F.Paste")
			(net "GND")
		)
		(pad "AG24" smd circle
			(at 7.50001 10.500004 180)
			(size 0.508 0.508)
			(layers "F.Cu" "F.Mask" "F.Paste")
			(net "NFP_SERDES1_RX0_N")
		)
		(pad "AG25" smd circle
			(at 8.500008 10.500004 180)
			(size 0.508 0.508)
			(layers "F.Cu" "F.Mask" "F.Paste")
			(net "GND")
		)
		(pad "AG26" smd circle
			(at 9.500006 10.500004 180)
			(size 0.508 0.508)
			(layers "F.Cu" "F.Mask" "F.Paste")
			(net "NFP_SERDES1_RX2_N")
		)
		(pad "AG27" smd circle
			(at 10.500004 10.500004 180)
			(size 0.508 0.508)
			(layers "F.Cu" "F.Mask" "F.Paste")
			(net "GND")
		)
		(pad "AG28" smd circle
			(at 11.500002 10.500004 180)
			(size 0.508 0.508)
			(layers "F.Cu" "F.Mask" "F.Paste")
			(net "GND")
		)
		(pad "AG29" smd circle
			(at 12.5 10.500004 180)
			(size 0.508 0.508)
			(layers "F.Cu" "F.Mask" "F.Paste")
			(net "GND")
		)
		(pad "AG30" smd circle
			(at 13.499998 10.500004 180)
			(size 0.508 0.508)
			(layers "F.Cu" "F.Mask" "F.Paste")
			(net "NFP_CORE_VID7")
		)
		(pad "AG31" smd circle
			(at 14.499996 10.500004 180)
			(size 0.508 0.508)
			(layers "F.Cu" "F.Mask" "F.Paste")
			(net "NFP_CORE_VID1")
		)
		(pad "AG32" smd circle
			(at 15.499994 10.500004 180)
			(size 0.508 0.508)
			(layers "F.Cu" "F.Mask" "F.Paste")
			(net "NFP_CORE_VID4")
		)
		(pad "AH1" smd circle
			(at -15.499994 11.500002 180)
			(size 0.508 0.508)
			(layers "F.Cu" "F.Mask" "F.Paste")
			(net "DDR0_32A_DM0")
		)
		(pad "AH2" smd circle
			(at -14.499996 11.500002 180)
			(size 0.508 0.508)
			(layers "F.Cu" "F.Mask" "F.Paste")
			(net "DDR_VDDQ")
		)
		(pad "AH3" smd circle
			(at -13.499998 11.500002 180)
			(size 0.508 0.508)
			(layers "F.Cu" "F.Mask" "F.Paste")
			(net "GND")
		)
		(pad "AH4" smd circle
			(at -12.5 11.500002 180)
			(size 0.508 0.508)
			(layers "F.Cu" "F.Mask" "F.Paste")
			(net "GND")
		)
		(pad "AH5" smd circle
			(at -11.500002 11.500002 180)
			(size 0.508 0.508)
			(layers "F.Cu" "F.Mask" "F.Paste")
			(net "GND")
		)
		(pad "AH6" smd circle
			(at -10.500004 11.500002 180)
			(size 0.508 0.508)
			(layers "F.Cu" "F.Mask" "F.Paste")
			(net "GND")
		)
		(pad "AH7" smd circle
			(at -9.500006 11.500002 180)
			(size 0.508 0.508)
			(layers "F.Cu" "F.Mask" "F.Paste")
			(net "GND")
		)
		(pad "AH8" smd circle
			(at -8.500008 11.500002 180)
			(size 0.508 0.508)
			(layers "F.Cu" "F.Mask" "F.Paste")
			(net "GND")
		)
		(pad "AH9" smd circle
			(at -7.50001 11.500002 180)
			(size 0.508 0.508)
			(layers "F.Cu" "F.Mask" "F.Paste")
			(net "GND")
		)
		(pad "AH10" smd circle
			(at -6.500012 11.500002 180)
			(size 0.508 0.508)
			(layers "F.Cu" "F.Mask" "F.Paste")
			(net "GND")
		)
		(pad "AH11" smd circle
			(at -5.499989 11.500002 180)
			(size 0.508 0.508)
			(layers "F.Cu" "F.Mask" "F.Paste")
			(net "GND")
		)
		(pad "AH12" smd circle
			(at -4.499991 11.500002 180)
			(size 0.508 0.508)
			(layers "F.Cu" "F.Mask" "F.Paste")
			(net "NFP_PCIE0_PET0_P")
		)
		(pad "AH13" smd circle
			(at -3.499993 11.500002 180)
			(size 0.508 0.508)
			(layers "F.Cu" "F.Mask" "F.Paste")
			(net "NFP_PCIE0_PET1_N")
		)
		(pad "AH14" smd circle
			(at -2.499995 11.500002 180)
			(size 0.508 0.508)
			(layers "F.Cu" "F.Mask" "F.Paste")
			(net "NFP_PCIE0_PET2_P")
		)
		(pad "AH15" smd circle
			(at -1.499997 11.500002 180)
			(size 0.508 0.508)
			(layers "F.Cu" "F.Mask" "F.Paste")
			(net "NFP_PCIE0_PET3_N")
		)
		(pad "AH16" smd circle
			(at -0.499999 11.500002 180)
			(size 0.508 0.508)
			(layers "F.Cu" "F.Mask" "F.Paste")
			(net "NFP_PCIE0_PET4_P")
		)
		(pad "AH17" smd circle
			(at 0.499999 11.500002 180)
			(size 0.508 0.508)
			(layers "F.Cu" "F.Mask" "F.Paste")
			(net "NFP_PCIE0_PET5_N")
		)
		(pad "AH18" smd circle
			(at 1.499997 11.500002 180)
			(size 0.508 0.508)
			(layers "F.Cu" "F.Mask" "F.Paste")
			(net "NFP_PCIE0_PET6_P")
		)
		(pad "AH19" smd circle
			(at 2.499995 11.500002 180)
			(size 0.508 0.508)
			(layers "F.Cu" "F.Mask" "F.Paste")
			(net "NFP_PCIE0_PET7_N")
		)
		(pad "AH20" smd circle
			(at 3.499993 11.500002 180)
			(size 0.508 0.508)
			(layers "F.Cu" "F.Mask" "F.Paste")
			(net "NFP_SERDES0_RX0_P")
		)
		(pad "AH21" smd circle
			(at 4.499991 11.500002 180)
			(size 0.508 0.508)
			(layers "F.Cu" "F.Mask" "F.Paste")
			(net "GND")
		)
		(pad "AH22" smd circle
			(at 5.499989 11.500002 180)
			(size 0.508 0.508)
			(layers "F.Cu" "F.Mask" "F.Paste")
			(net "GND")
		)
		(pad "AH23" smd circle
			(at 6.500012 11.500002 180)
			(size 0.508 0.508)
			(layers "F.Cu" "F.Mask" "F.Paste")
			(net "GND")
		)
		(pad "AH24" smd circle
			(at 7.50001 11.500002 180)
			(size 0.508 0.508)
			(layers "F.Cu" "F.Mask" "F.Paste")
			(net "NFP_SERDES1_RX0_P")
		)
		(pad "AH25" smd circle
			(at 8.500008 11.500002 180)
			(size 0.508 0.508)
			(layers "F.Cu" "F.Mask" "F.Paste")
			(net "NFP_SERDES1_RX1_N")
		)
		(pad "AH26" smd circle
			(at 9.500006 11.500002 180)
			(size 0.508 0.508)
			(layers "F.Cu" "F.Mask" "F.Paste")
			(net "NFP_SERDES1_RX2_P")
		)
		(pad "AH27" smd circle
			(at 10.500004 11.500002 180)
			(size 0.508 0.508)
			(layers "F.Cu" "F.Mask" "F.Paste")
			(net "NFP_SERDES1_RX3_N")
		)
		(pad "AH28" smd circle
			(at 11.500002 11.500002 180)
			(size 0.508 0.508)
			(layers "F.Cu" "F.Mask" "F.Paste")
			(net "GND")
		)
		(pad "AH29" smd circle
			(at 12.5 11.500002 180)
			(size 0.508 0.508)
			(layers "F.Cu" "F.Mask" "F.Paste")
			(net "GND")
		)
		(pad "AH30" smd circle
			(at 13.499998 11.500002 180)
			(size 0.508 0.508)
			(layers "F.Cu" "F.Mask" "F.Paste")
			(net "GND")
		)
		(pad "AH31" smd circle
			(at 14.499996 11.500002 180)
			(size 0.508 0.508)
			(layers "F.Cu" "F.Mask" "F.Paste")
			(net "NFP_CORE_VID5")
		)
		(pad "AH32" smd circle
			(at 15.499994 11.500002 180)
			(size 0.508 0.508)
			(layers "F.Cu" "F.Mask" "F.Paste")
			(net "NFP_CORE_VID2")
		)
		(pad "AJ1" smd circle
			(at -15.499994 12.5 180)
			(size 0.508 0.508)
			(layers "F.Cu" "F.Mask" "F.Paste")
			(net "GND")
		)
		(pad "AJ2" smd circle
			(at -14.499996 12.5 180)
			(size 0.508 0.508)
			(layers "F.Cu" "F.Mask" "F.Paste")
			(net "GND")
		)
		(pad "AJ3" smd circle
			(at -13.499998 12.5 180)
			(size 0.508 0.508)
			(layers "F.Cu" "F.Mask" "F.Paste")
			(net "GND")
		)
		(pad "AJ4" smd circle
			(at -12.5 12.5 180)
			(size 0.508 0.508)
			(layers "F.Cu" "F.Mask" "F.Paste")
			(net "GND")
		)
		(pad "AJ5" smd circle
			(at -11.500002 12.5 180)
			(size 0.508 0.508)
			(layers "F.Cu" "F.Mask" "F.Paste")
			(net "GND")
		)
		(pad "AJ6" smd circle
			(at -10.500004 12.5 180)
			(size 0.508 0.508)
			(layers "F.Cu" "F.Mask" "F.Paste")
			(net "GND")
		)
		(pad "AJ7" smd circle
			(at -9.500006 12.5 180)
			(size 0.508 0.508)
			(layers "F.Cu" "F.Mask" "F.Paste")
			(net "GND")
		)
		(pad "AJ8" smd circle
			(at -8.500008 12.5 180)
			(size 0.508 0.508)
			(layers "F.Cu" "F.Mask" "F.Paste")
			(net "GND")
		)
		(pad "AJ9" smd circle
			(at -7.50001 12.5 180)
			(size 0.508 0.508)
			(layers "F.Cu" "F.Mask" "F.Paste")
			(net "GND")
		)
		(pad "AJ10" smd circle
			(at -6.500012 12.5 180)
			(size 0.508 0.508)
			(layers "F.Cu" "F.Mask" "F.Paste")
			(net "GND")
		)
		(pad "AJ11" smd circle
			(at -5.499989 12.5 180)
			(size 0.508 0.508)
			(layers "F.Cu" "F.Mask" "F.Paste")
			(net "GND")
		)
		(pad "AJ12" smd circle
			(at -4.499991 12.5 180)
			(size 0.508 0.508)
			(layers "F.Cu" "F.Mask" "F.Paste")
			(net "GND")
		)
		(pad "AJ13" smd circle
			(at -3.499993 12.5 180)
			(size 0.508 0.508)
			(layers "F.Cu" "F.Mask" "F.Paste")
			(net "NFP_PCIE0_PET1_P")
		)
		(pad "AJ14" smd circle
			(at -2.499995 12.5 180)
			(size 0.508 0.508)
			(layers "F.Cu" "F.Mask" "F.Paste")
			(net "GND")
		)
		(pad "AJ15" smd circle
			(at -1.499997 12.5 180)
			(size 0.508 0.508)
			(layers "F.Cu" "F.Mask" "F.Paste")
			(net "NFP_PCIE0_PET3_P")
		)
		(pad "AJ16" smd circle
			(at -0.499999 12.5 180)
			(size 0.508 0.508)
			(layers "F.Cu" "F.Mask" "F.Paste")
			(net "GND")
		)
		(pad "AJ17" smd circle
			(at 0.499999 12.5 180)
			(size 0.508 0.508)
			(layers "F.Cu" "F.Mask" "F.Paste")
			(net "NFP_PCIE0_PET5_P")
		)
		(pad "AJ18" smd circle
			(at 1.499997 12.5 180)
			(size 0.508 0.508)
			(layers "F.Cu" "F.Mask" "F.Paste")
			(net "GND")
		)
		(pad "AJ19" smd circle
			(at 2.499995 12.5 180)
			(size 0.508 0.508)
			(layers "F.Cu" "F.Mask" "F.Paste")
			(net "NFP_PCIE0_PET7_P")
		)
		(pad "AJ20" smd circle
			(at 3.499993 12.5 180)
			(size 0.508 0.508)
			(layers "F.Cu" "F.Mask" "F.Paste")
			(net "GND")
		)
		(pad "AJ21" smd circle
			(at 4.499991 12.5 180)
			(size 0.508 0.508)
			(layers "F.Cu" "F.Mask" "F.Paste")
			(net "GND")
		)
		(pad "AJ22" smd circle
			(at 5.499989 12.5 180)
			(size 0.508 0.508)
			(layers "F.Cu" "F.Mask" "F.Paste")
			(net "GND")
		)
		(pad "AJ23" smd circle
			(at 6.500012 12.5 180)
			(size 0.508 0.508)
			(layers "F.Cu" "F.Mask" "F.Paste")
			(net "GND")
		)
		(pad "AJ24" smd circle
			(at 7.50001 12.5 180)
			(size 0.508 0.508)
			(layers "F.Cu" "F.Mask" "F.Paste")
			(net "GND")
		)
		(pad "AJ25" smd circle
			(at 8.500008 12.5 180)
			(size 0.508 0.508)
			(layers "F.Cu" "F.Mask" "F.Paste")
			(net "NFP_SERDES1_RX1_P")
		)
		(pad "AJ26" smd circle
			(at 9.500006 12.5 180)
			(size 0.508 0.508)
			(layers "F.Cu" "F.Mask" "F.Paste")
			(net "GND")
		)
		(pad "AJ27" smd circle
			(at 10.500004 12.5 180)
			(size 0.508 0.508)
			(layers "F.Cu" "F.Mask" "F.Paste")
			(net "NFP_SERDES1_RX3_P")
		)
		(pad "AJ28" smd circle
			(at 11.500002 12.5 180)
			(size 0.508 0.508)
			(layers "F.Cu" "F.Mask" "F.Paste")
			(net "GND")
		)
		(pad "AJ29" smd circle
			(at 12.5 12.5 180)
			(size 0.508 0.508)
			(layers "F.Cu" "F.Mask" "F.Paste")
			(net "GND")
		)
		(pad "AJ30" smd circle
			(at 13.499998 12.5 180)
			(size 0.508 0.508)
			(layers "F.Cu" "F.Mask" "F.Paste")
			(net "GND")
		)
		(pad "AJ31" smd circle
			(at 14.499996 12.5 180)
			(size 0.508 0.508)
			(layers "F.Cu" "F.Mask" "F.Paste")
			(net "NFP_CORE_VID0")
		)
		(pad "AJ32" smd circle
			(at 15.499994 12.5 180)
			(size 0.508 0.508)
			(layers "F.Cu" "F.Mask" "F.Paste")
			(net "NFP_CORE_VID3")
		)
		(pad "AK1" smd circle
			(at -15.499994 13.499998 180)
			(size 0.6604 0.6604)
			(layers "F.Cu" "F.Mask" "F.Paste")
			(net "GND")
		)
		(pad "AK2" smd circle
			(at -14.499996 13.499998 180)
			(size 0.508 0.508)
			(layers "F.Cu" "F.Mask" "F.Paste")
			(net "GND")
		)
		(pad "AK3" smd circle
			(at -13.499998 13.499998 180)
			(size 0.508 0.508)
			(layers "F.Cu" "F.Mask" "F.Paste")
			(net "GND")
		)
		(pad "AK4" smd circle
			(at -12.5 13.499998 180)
			(size 0.508 0.508)
			(layers "F.Cu" "F.Mask" "F.Paste")
			(net "_NC_NFP_PCIE1_PET0_N")
		)
		(pad "AK5" smd circle
			(at -11.500002 13.499998 180)
			(size 0.508 0.508)
			(layers "F.Cu" "F.Mask" "F.Paste")
			(net "GND")
		)
		(pad "AK6" smd circle
			(at -10.500004 13.499998 180)
			(size 0.508 0.508)
			(layers "F.Cu" "F.Mask" "F.Paste")
			(net "_NC_NFP_PCIE1_PET2_N")
		)
		(pad "AK7" smd circle
			(at -9.500006 13.499998 180)
			(size 0.508 0.508)
			(layers "F.Cu" "F.Mask" "F.Paste")
			(net "GND")
		)
		(pad "AK8" smd circle
			(at -8.500008 13.499998 180)
			(size 0.508 0.508)
			(layers "F.Cu" "F.Mask" "F.Paste")
			(net "_NC_NFP_PCIE1_PET4_N")
		)
		(pad "AK9" smd circle
			(at -7.50001 13.499998 180)
			(size 0.508 0.508)
			(layers "F.Cu" "F.Mask" "F.Paste")
			(net "GND")
		)
		(pad "AK10" smd circle
			(at -6.500012 13.499998 180)
			(size 0.508 0.508)
			(layers "F.Cu" "F.Mask" "F.Paste")
			(net "_NC_NFP_PCIE1_PET6_N")
		)
		(pad "AK11" smd circle
			(at -5.499989 13.499998 180)
			(size 0.508 0.508)
			(layers "F.Cu" "F.Mask" "F.Paste")
			(net "GND")
		)
		(pad "AK12" smd circle
			(at -4.499991 13.499998 180)
			(size 0.508 0.508)
			(layers "F.Cu" "F.Mask" "F.Paste")
			(net "_NFP_PCIE0_PER0_N")
		)
		(pad "AK13" smd circle
			(at -3.499993 13.499998 180)
			(size 0.508 0.508)
			(layers "F.Cu" "F.Mask" "F.Paste")
			(net "GND")
		)
		(pad "AK14" smd circle
			(at -2.499995 13.499998 180)
			(size 0.508 0.508)
			(layers "F.Cu" "F.Mask" "F.Paste")
			(net "_NFP_PCIE0_PER2_N")
		)
		(pad "AK15" smd circle
			(at -1.499997 13.499998 180)
			(size 0.508 0.508)
			(layers "F.Cu" "F.Mask" "F.Paste")
			(net "GND")
		)
		(pad "AK16" smd circle
			(at -0.499999 13.499998 180)
			(size 0.508 0.508)
			(layers "F.Cu" "F.Mask" "F.Paste")
			(net "_NFP_PCIE0_PER4_N")
		)
		(pad "AK17" smd circle
			(at 0.499999 13.499998 180)
			(size 0.508 0.508)
			(layers "F.Cu" "F.Mask" "F.Paste")
			(net "GND")
		)
		(pad "AK18" smd circle
			(at 1.499997 13.499998 180)
			(size 0.508 0.508)
			(layers "F.Cu" "F.Mask" "F.Paste")
			(net "_NFP_PCIE0_PER6_N")
		)
		(pad "AK19" smd circle
			(at 2.499995 13.499998 180)
			(size 0.508 0.508)
			(layers "F.Cu" "F.Mask" "F.Paste")
			(net "GND")
		)
		(pad "AK20" smd circle
			(at 3.499993 13.499998 180)
			(size 0.508 0.508)
			(layers "F.Cu" "F.Mask" "F.Paste")
			(net "NFP_SERDES0_TX0_N")
		)
		(pad "AK21" smd circle
			(at 4.499991 13.499998 180)
			(size 0.508 0.508)
			(layers "F.Cu" "F.Mask" "F.Paste")
			(net "GND")
		)
		(pad "AK22" smd circle
			(at 5.499989 13.499998 180)
			(size 0.508 0.508)
			(layers "F.Cu" "F.Mask" "F.Paste")
			(net "_NC_NFP_SERDES0_TX2_N")
		)
		(pad "AK23" smd circle
			(at 6.500012 13.499998 180)
			(size 0.508 0.508)
			(layers "F.Cu" "F.Mask" "F.Paste")
			(net "GND")
		)
		(pad "AK24" smd circle
			(at 7.50001 13.499998 180)
			(size 0.508 0.508)
			(layers "F.Cu" "F.Mask" "F.Paste")
			(net "NFP_SERDES1_TX0_N")
		)
		(pad "AK25" smd circle
			(at 8.500008 13.499998 180)
			(size 0.508 0.508)
			(layers "F.Cu" "F.Mask" "F.Paste")
			(net "GND")
		)
		(pad "AK26" smd circle
			(at 9.500006 13.499998 180)
			(size 0.508 0.508)
			(layers "F.Cu" "F.Mask" "F.Paste")
			(net "NFP_SERDES1_TX2_N")
		)
		(pad "AK27" smd circle
			(at 10.500004 13.499998 180)
			(size 0.508 0.508)
			(layers "F.Cu" "F.Mask" "F.Paste")
			(net "GND")
		)
		(pad "AK28" smd circle
			(at 11.500002 13.499998 180)
			(size 0.508 0.508)
			(layers "F.Cu" "F.Mask" "F.Paste")
			(net "_NC_NFP_SERDES2_TX0_N")
		)
		(pad "AK29" smd circle
			(at 12.5 13.499998 180)
			(size 0.508 0.508)
			(layers "F.Cu" "F.Mask" "F.Paste")
			(net "GND")
		)
		(pad "AK30" smd circle
			(at 13.499998 13.499998 180)
			(size 0.508 0.508)
			(layers "F.Cu" "F.Mask" "F.Paste")
			(net "GND")
		)
		(pad "AK31" smd circle
			(at 14.499996 13.499998 180)
			(size 0.508 0.508)
			(layers "F.Cu" "F.Mask" "F.Paste")
			(net "_NC_NFP_TEST_EDM")
		)
	)
)
